(kicad_pcb
	(version 20241229)
	(generator "pcbnew")
	(generator_version "9.0")
	(general
		(thickness 1.711)
		(legacy_teardrops no)
	)
	(paper "A4")
	(title_block
		(title "Antmicro Baseboard for Jetson AGX Thor")
		(date "2026-02-18")
		(rev "1.1.0")
		(company "Antmicro Ltd")
		(comment 1 "www.antmicro.com")
		(comment 9 "footprints 226-230 of 1170")
	)
	(layers
		(0 "F.Cu" signal)
		(4 "In1.Cu" signal)
		(6 "In2.Cu" signal)
		(8 "In3.Cu" signal)
		(10 "In4.Cu" jumper)
		(12 "In5.Cu" signal)
		(14 "In6.Cu" signal)
		(16 "In7.Cu" signal)
		(18 "In8.Cu" signal)
		(2 "B.Cu" signal)
		(9 "F.Adhes" user "F.Adhesive")
		(11 "B.Adhes" user "B.Adhesive")
		(13 "F.Paste" user)
		(15 "B.Paste" user)
		(5 "F.SilkS" user "F.Silkscreen")
		(7 "B.SilkS" user "B.Silkscreen")
		(1 "F.Mask" user)
		(3 "B.Mask" user)
		(17 "Dwgs.User" user "User.Drawings")
		(19 "Cmts.User" user "User.Comments")
		(21 "Eco1.User" user "User.Eco1")
		(23 "Eco2.User" user "User.Eco2")
		(25 "Edge.Cuts" user)
		(27 "Margin" user)
		(31 "F.CrtYd" user "F.Courtyard")
		(29 "B.CrtYd" user "B.Courtyard")
		(35 "F.Fab" user)
		(33 "B.Fab" user)
	)
	(footprint "antmicro-footprints:R_0805_2012Metric"
		(layer "F.Cu")
		(at 172.4 115.966 180)
		(property "Reference" "R77"
			(at 2.12 0.366 0)
			(layer "F.SilkS")
			(effects
				(font
					(size 0.7 0.7)
					(thickness 0.15)
				)
				(justify right top)
			)
		)
		(property "Value" "R_0R001_0805"
			(at 0 1.8 0)
			(layer "F.Fab")
			(effects
				(font
					(size 0.7 0.7)
					(thickness 0.15)
				)
				(justify right top)
			)
		)
		(property "Datasheet" "https://www.eaton.com/content/dam/eaton/products/electronic-components/resources/data-sheet/eaton-msma-automotive-smd-current-sense-resistor-metal-strip-data-sheet-elx1179.pdf"
			(at 0 0 0)
			(layer "F.Fab")
			(hide yes)
			(effects
				(font
					(size 1.27 1.27)
					(thickness 0.15)
				)
			)
		)
		(property "Description" "Current Sense Resistors - SMD MSMA, 0805 SIZE, 1/2 Watt, 1 mohm, 50 TCR MnCu Metal AEC-Q"
			(at 0 0 0)
			(layer "F.Fab")
			(hide yes)
			(effects
				(font
					(size 1.27 1.27)
					(thickness 0.15)
				)
			)
		)
		(property "MPN" "MSMA0805R0010FSM"
			(at 0 0 180)
			(unlocked yes)
			(layer "F.Fab")
			(hide yes)
			(effects
				(font
					(size 1 1)
					(thickness 0.15)
				)
			)
		)
		(property "Manufacturer" "Eaton"
			(at 0 0 180)
			(unlocked yes)
			(layer "F.Fab")
			(hide yes)
			(effects
				(font
					(size 1 1)
					(thickness 0.15)
				)
			)
		)
		(property "License" "Apache-2.0"
			(at 0 0 180)
			(unlocked yes)
			(layer "F.Fab")
			(hide yes)
			(effects
				(font
					(size 1 1)
					(thickness 0.15)
				)
			)
		)
		(property "Author" "Antmicro"
			(at 0 0 180)
			(unlocked yes)
			(layer "F.Fab")
			(hide yes)
			(effects
				(font
					(size 1 1)
					(thickness 0.15)
				)
			)
		)
		(property "Val" "0R001"
			(at 0 0 180)
			(unlocked yes)
			(layer "F.Fab")
			(hide yes)
			(effects
				(font
					(size 1 1)
					(thickness 0.15)
				)
			)
		)
		(property "Tolerance" "1%"
			(at 0 0 180)
			(unlocked yes)
			(layer "F.Fab")
			(hide yes)
			(effects
				(font
					(size 1 1)
					(thickness 0.15)
				)
			)
		)
		(property "Public" "False"
			(at 0 0 180)
			(unlocked yes)
			(layer "F.Fab")
			(hide yes)
			(effects
				(font
					(size 1 1)
					(thickness 0.15)
				)
			)
		)
		(sheetname "/DCDC/")
		(sheetfile "dcdc.kicad_sch")
		(attr smd)
		(fp_line
			(start -0.3 -0.701)
			(end 0.298 -0.701)
			(stroke
				(width 0.15)
				(type solid)
			)
			(layer "F.SilkS")
		)
		(fp_line
			(start -0.32 0.699)
			(end 0.28 0.699)
			(stroke
				(width 0.15)
				(type solid)
			)
			(layer "F.SilkS")
		)
		(fp_rect
			(start 1.95 -0.9)
			(end -1.95 0.9)
			(stroke
				(width 0.05)
				(type default)
			)
			(fill no)
			(layer "F.CrtYd")
		)
		(fp_line
			(start 0.949 -0.677)
			(end 0.949 0.675)
			(stroke
				(width 0.15)
				(type solid)
			)
			(layer "F.Fab")
		)
		(fp_line
			(start -0.951 0.68)
			(end 0.949 0.68)
			(stroke
				(width 0.15)
				(type solid)
			)
			(layer "F.Fab")
		)
		(fp_line
			(start -0.951 -0.677)
			(end -0.951 0.675)
			(stroke
				(width 0.15)
				(type solid)
			)
			(layer "F.Fab")
		)
		(fp_line
			(start -0.951 -0.682)
			(end 0.949 -0.682)
			(stroke
				(width 0.15)
				(type solid)
			)
			(layer "F.Fab")
		)
		(fp_text user "Author: Antmicro"
			(at -1.9 4.4 0)
			(layer "F.Fab")
			(effects
				(font
					(size 0.7 0.7)
					(thickness 0.15)
				)
				(justify right top)
			)
		)
		(fp_text user "License: Apache-2.0"
			(at -1.9 5.75 0)
			(layer "F.Fab")
			(effects
				(font
					(size 0.7 0.7)
					(thickness 0.15)
				)
				(justify right top)
			)
		)
		(fp_text user "${REFERENCE}"
			(at -1.9 3.1 0)
			(layer "F.Fab")
			(effects
				(font
					(size 0.7 0.7)
					(thickness 0.15)
				)
				(justify right top)
			)
		)
		(pad "1" smd roundrect
			(at -1.1 0 180)
			(size 1.2 1.3)
			(layers "F.Cu" "F.Mask" "F.Paste")
			(roundrect_rratio 0.25)
			(net 253 "/DCDC/5V_OUT")
			(pintype "passive")
		)
		(pad "2" smd roundrect
			(at 1.1 0 180)
			(size 1.2 1.3)
			(layers "F.Cu" "F.Mask" "F.Paste")
			(roundrect_rratio 0.25)
			(net 5 "+5V")
			(pintype "passive")
		)
	)
	(footprint "antmicro-footprints:C_0402_1005Metric"
		(layer "F.Cu")
		(at 212.912407 98.212991 90)
		(descr "Capacitor SMD 0402")
		(tags "capacitor SMD 0402")
		(property "Reference" "C231"
			(at -1.787009 -2.612407 90)
			(layer "F.SilkS")
			(effects
				(font
					(size 0.7 0.7)
					(thickness 0.15)
				)
				(justify left bottom)
			)
		)
		(property "Value" "C_10u_0402"
			(at -1.022927 2.155213 90)
			(layer "F.Fab")
			(effects
				(font
					(size 0.7 0.7)
					(thickness 0.15)
				)
				(justify left bottom)
			)
		)
		(property "Datasheet" "https://www.yageo.com/en/Chart/Download/pdf/CC0402MRX5R5BB106"
			(at 0 0 90)
			(layer "F.Fab")
			(hide yes)
			(effects
				(font
					(size 1.27 1.27)
					(thickness 0.15)
				)
			)
		)
		(property "Description" "SMD Multilayer Ceramic Capacitor, 10 µF, 6.3 V, 0402 [1005 Metric], ± 20%, X5R, CC Series"
			(at 0 0 90)
			(layer "F.Fab")
			(hide yes)
			(effects
				(font
					(size 1.27 1.27)
					(thickness 0.15)
				)
			)
		)
		(property "Manufacturer" "YAGEO"
			(at 0 0 270)
			(unlocked yes)
			(layer "F.Fab")
			(hide yes)
			(effects
				(font
					(size 1 1)
					(thickness 0.15)
				)
			)
		)
		(property "MPN" "CC0402MRX5R5BB106"
			(at 0 0 270)
			(unlocked yes)
			(layer "F.Fab")
			(hide yes)
			(effects
				(font
					(size 1 1)
					(thickness 0.15)
				)
			)
		)
		(property "Val" "10u"
			(at 0 0 270)
			(unlocked yes)
			(layer "F.Fab")
			(hide yes)
			(effects
				(font
					(size 1 1)
					(thickness 0.15)
				)
			)
		)
		(property "License" "Apache-2.0"
			(at 0 0 270)
			(unlocked yes)
			(layer "F.Fab")
			(hide yes)
			(effects
				(font
					(size 1 1)
					(thickness 0.15)
				)
			)
		)
		(property "Author" "Antmicro"
			(at 0 0 270)
			(unlocked yes)
			(layer "F.Fab")
			(hide yes)
			(effects
				(font
					(size 1 1)
					(thickness 0.15)
				)
			)
		)
		(property "Voltage" ""
			(at 0 0 270)
			(unlocked yes)
			(layer "F.Fab")
			(hide yes)
			(effects
				(font
					(size 1 1)
					(thickness 0.15)
				)
			)
		)
		(property "Dielectric" "template_dielectric"
			(at 0 0 270)
			(unlocked yes)
			(layer "F.Fab")
			(hide yes)
			(effects
				(font
					(size 1 1)
					(thickness 0.15)
				)
			)
		)
		(sheetname "/Recovery USB/")
		(sheetfile "recovery_usb.kicad_sch")
		(attr smd)
		(fp_poly
			(pts
				(xy -0.925 -0.47) (xy 0.925 -0.47) (xy 0.925 0.47) (xy -0.925 0.47)
			)
			(stroke
				(width 0.05)
				(type default)
			)
			(fill no)
			(layer "F.CrtYd")
		)
		(fp_line
			(start 0.504 -0.25)
			(end 0.504 0.248)
			(stroke
				(width 0.15)
				(type solid)
			)
			(layer "F.Fab")
		)
		(fp_line
			(start -0.494 -0.25)
			(end 0.504 -0.25)
			(stroke
				(width 0.15)
				(type solid)
			)
			(layer "F.Fab")
		)
		(fp_line
			(start 0.504 0.248)
			(end -0.494 0.248)
			(stroke
				(width 0.15)
				(type solid)
			)
			(layer "F.Fab")
		)
		(fp_line
			(start -0.494 0.248)
			(end -0.494 -0.25)
			(stroke
				(width 0.15)
				(type solid)
			)
			(layer "F.Fab")
		)
		(fp_text user "License: Apache-2.0"
			(at -0.939 5.799 90)
			(layer "F.Fab")
			(effects
				(font
					(size 0.7 0.7)
					(thickness 0.15)
				)
				(justify left bottom)
			)
		)
		(fp_text user "${REFERENCE}"
			(at -0.939 4.599 90)
			(layer "F.Fab")
			(effects
				(font
					(size 0.7 0.7)
					(thickness 0.15)
				)
				(justify left bottom)
			)
		)
		(fp_text user "Author: Antmicro"
			(at -0.939 3.399 90)
			(layer "F.Fab")
			(effects
				(font
					(size 0.7 0.7)
					(thickness 0.15)
				)
				(justify left bottom)
			)
		)
		(pad "1" smd roundrect
			(at -0.48 0 90)
			(size 0.59 0.64)
			(layers "F.Cu" "F.Mask" "F.Paste")
			(roundrect_rratio 0.25)
			(net 5 "+5V")
			(pintype "passive")
		)
		(pad "2" smd roundrect
			(at 0.48 0 90)
			(size 0.59 0.64)
			(layers "F.Cu" "F.Mask" "F.Paste")
			(roundrect_rratio 0.25)
			(net 1 "GND")
			(pintype "passive")
		)
	)
	(footprint "antmicro-footprints:C_0402_1005Metric"
		(layer "F.Cu")
		(at 162.228936 99.57)
		(descr "Capacitor SMD 0402")
		(tags "capacitor SMD 0402")
		(property "Reference" "C385"
			(at -5.828936 0.43 0)
			(layer "F.SilkS")
			(effects
				(font
					(size 0.7 0.7)
					(thickness 0.15)
				)
				(justify left bottom)
			)
		)
		(property "Value" "C_100n_0402"
			(at -1.022927 2.155213 0)
			(layer "F.Fab")
			(effects
				(font
					(size 0.7 0.7)
					(thickness 0.15)
				)
				(justify left bottom)
			)
		)
		(property "Datasheet" "https://www.murata.com/products/productdetail?partno=GRM155R61H104KE14%23"
			(at 0 0 0)
			(layer "F.Fab")
			(hide yes)
			(effects
				(font
					(size 1.27 1.27)
					(thickness 0.15)
				)
			)
		)
		(property "Description" "SMD Multilayer Ceramic Capacitor, 0.1 µF, 50 V, 0402 [1005 Metric], ± 10%, X5R, GRM Series"
			(at 0 0 0)
			(layer "F.Fab")
			(hide yes)
			(effects
				(font
					(size 1.27 1.27)
					(thickness 0.15)
				)
			)
		)
		(property "Manufacturer" "Murata"
			(at 0 0 0)
			(unlocked yes)
			(layer "F.Fab")
			(hide yes)
			(effects
				(font
					(size 1 1)
					(thickness 0.15)
				)
			)
		)
		(property "MPN" "GRM155R61H104KE14D"
			(at 0 0 0)
			(unlocked yes)
			(layer "F.Fab")
			(hide yes)
			(effects
				(font
					(size 1 1)
					(thickness 0.15)
				)
			)
		)
		(property "Val" "100n"
			(at 0 0 0)
			(unlocked yes)
			(layer "F.Fab")
			(hide yes)
			(effects
				(font
					(size 1 1)
					(thickness 0.15)
				)
			)
		)
		(property "License" "Apache-2.0"
			(at 0 0 0)
			(unlocked yes)
			(layer "F.Fab")
			(hide yes)
			(effects
				(font
					(size 1 1)
					(thickness 0.15)
				)
			)
		)
		(property "Author" "Antmicro"
			(at 0 0 0)
			(unlocked yes)
			(layer "F.Fab")
			(hide yes)
			(effects
				(font
					(size 1 1)
					(thickness 0.15)
				)
			)
		)
		(property "Voltage" "50V"
			(at 0 0 0)
			(unlocked yes)
			(layer "F.Fab")
			(hide yes)
			(effects
				(font
					(size 1 1)
					(thickness 0.15)
				)
			)
		)
		(property "Dielectric" "X5R"
			(at 0 0 0)
			(unlocked yes)
			(layer "F.Fab")
			(hide yes)
			(effects
				(font
					(size 1 1)
					(thickness 0.15)
				)
			)
		)
		(component_classes
			(class "DCDC_SOM")
		)
		(sheetname "/DCDC/")
		(sheetfile "dcdc.kicad_sch")
		(attr smd)
		(fp_rect
			(start -0.925 -0.47)
			(end 0.925 0.47)
			(stroke
				(width 0.05)
				(type default)
			)
			(fill no)
			(layer "F.CrtYd")
		)
		(fp_line
			(start -0.494 -0.25)
			(end 0.504 -0.25)
			(stroke
				(width 0.15)
				(type solid)
			)
			(layer "F.Fab")
		)
		(fp_line
			(start -0.494 0.248)
			(end -0.494 -0.25)
			(stroke
				(width 0.15)
				(type solid)
			)
			(layer "F.Fab")
		)
		(fp_line
			(start 0.504 -0.25)
			(end 0.504 0.248)
			(stroke
				(width 0.15)
				(type solid)
			)
			(layer "F.Fab")
		)
		(fp_line
			(start 0.504 0.248)
			(end -0.494 0.248)
			(stroke
				(width 0.15)
				(type solid)
			)
			(layer "F.Fab")
		)
		(fp_text user "License: Apache-2.0"
			(at -0.939 5.799 0)
			(layer "F.Fab")
			(effects
				(font
					(size 0.7 0.7)
					(thickness 0.15)
				)
				(justify left bottom)
			)
		)
		(fp_text user "Author: Antmicro"
			(at -0.939 3.399 0)
			(layer "F.Fab")
			(effects
				(font
					(size 0.7 0.7)
					(thickness 0.15)
				)
				(justify left bottom)
			)
		)
		(fp_text user "${REFERENCE}"
			(at -0.939 4.599 0)
			(layer "F.Fab")
			(effects
				(font
					(size 0.7 0.7)
					(thickness 0.15)
				)
				(justify left bottom)
			)
		)
		(pad "1" smd roundrect
			(at -0.48 0)
			(size 0.59 0.64)
			(layers "F.Cu" "F.Mask" "F.Paste")
			(roundrect_rratio 0.25)
			(net 1187 "Net-(U22-IN-)")
			(pintype "passive")
		)
		(pad "2" smd roundrect
			(at 0.48 0)
			(size 0.59 0.64)
			(layers "F.Cu" "F.Mask" "F.Paste")
			(roundrect_rratio 0.25)
			(net 1283 "Net-(U22-IN+)")
			(pintype "passive")
		)
	)
	(footprint "antmicro-footprints:TP_SMD_0.75mm"
		(layer "F.Cu")
		(at 166.25 57.12)
		(property "Reference" "TP41"
			(at -0.831064 2.21 90)
			(layer "F.SilkS")
			(hide yes)
			(effects
				(font
					(size 0.7 0.7)
					(thickness 0.15)
				)
				(justify left bottom)
			)
		)
		(property "Value" "TP_0.75mm_SMD"
			(at 0 1.2 0)
			(layer "F.Fab")
			(effects
				(font
					(size 0.7 0.7)
					(thickness 0.15)
				)
				(justify left bottom)
			)
		)
		(property "Description" "SMT test point"
			(at 0 0 0)
			(layer "F.Fab")
			(hide yes)
			(effects
				(font
					(size 1.27 1.27)
					(thickness 0.15)
				)
			)
		)
		(property "MPN" ""
			(at 0 0 0)
			(unlocked yes)
			(layer "F.Fab")
			(hide yes)
			(effects
				(font
					(size 1 1)
					(thickness 0.15)
				)
			)
		)
		(property "Manufacturer" ""
			(at 0 0 0)
			(unlocked yes)
			(layer "F.Fab")
			(hide yes)
			(effects
				(font
					(size 1 1)
					(thickness 0.15)
				)
			)
		)
		(property "Author" "Antmicro"
			(at 0 0 0)
			(unlocked yes)
			(layer "F.Fab")
			(hide yes)
			(effects
				(font
					(size 1 1)
					(thickness 0.15)
				)
			)
		)
		(property "License" "Apache-2.0"
			(at 0 0 0)
			(unlocked yes)
			(layer "F.Fab")
			(hide yes)
			(effects
				(font
					(size 1 1)
					(thickness 0.15)
				)
			)
		)
		(sheetname "/Power/")
		(sheetfile "power.kicad_sch")
		(attr exclude_from_pos_files exclude_from_bom)
		(fp_circle
			(center 0 0)
			(end 0.475 0)
			(stroke
				(width 0.05)
				(type default)
			)
			(fill no)
			(layer "F.CrtYd")
		)
		(fp_text user "${REFERENCE}"
			(at -0.4 2.7 0)
			(layer "F.Fab")
			(effects
				(font
					(size 0.7 0.7)
					(thickness 0.15)
				)
				(justify left bottom)
			)
		)
		(fp_text user "License: Apache-2.0"
			(at -0.4 5.101 0)
			(layer "F.Fab")
			(effects
				(font
					(size 0.7 0.7)
					(thickness 0.15)
				)
				(justify left bottom)
			)
		)
		(fp_text user "Author: Antmicro"
			(at -0.4 3.901 0)
			(layer "F.Fab")
			(effects
				(font
					(size 0.7 0.7)
					(thickness 0.15)
				)
				(justify left bottom)
			)
		)
		(pad "1" smd circle
			(at 0 0)
			(size 0.75 0.75)
			(layers "F.Cu" "F.Mask")
			(net 2 "+3V3")
			(pinfunction "1")
			(pintype "passive")
		)
	)
	(footprint "antmicro-footprints:Vishay_PowerPAK_1212-8_Single"
		(layer "F.Cu")
		(at 211.214 68.81 180)
		(descr "PowerPAK 1212-8 Single")
		(tags "Vishay PowerPAK 1212-8 Single")
		(property "Reference" "Q42"
			(at 2.914 1.81 90)
			(layer "F.SilkS")
			(effects
				(font
					(size 0.7 0.7)
					(thickness 0.15)
				)
				(justify right top)
			)
		)
		(property "Value" "SISS05DN-T1-GE3"
			(at 0 2.7 0)
			(layer "F.Fab")
			(effects
				(font
					(size 0.7 0.7)
					(thickness 0.15)
				)
				(justify right top)
			)
		)
		(property "Datasheet" "https://www.vishay.com/docs/77029/siss05dn.pdf"
			(at 0 0 0)
			(layer "F.Fab")
			(hide yes)
			(effects
				(font
					(size 1.27 1.27)
					(thickness 0.15)
				)
			)
		)
		(property "Description" "Power MOSFET, P Channel, 30 V, 108 A, 0.0035 ohm, PowerPAK 1212, Surface Mount"
			(at 0 0 0)
			(layer "F.Fab")
			(hide yes)
			(effects
				(font
					(size 1.27 1.27)
					(thickness 0.15)
				)
			)
		)
		(property "MPN" "SISS05DN-T1-GE3"
			(at 0 0 180)
			(unlocked yes)
			(layer "F.Fab")
			(hide yes)
			(effects
				(font
					(size 1 1)
					(thickness 0.15)
				)
			)
		)
		(property "Manufacturer" "Vishay"
			(at 0 0 180)
			(unlocked yes)
			(layer "F.Fab")
			(hide yes)
			(effects
				(font
					(size 1 1)
					(thickness 0.15)
				)
			)
		)
		(property "Author" "Antmicro"
			(at 0 0 180)
			(unlocked yes)
			(layer "F.Fab")
			(hide yes)
			(effects
				(font
					(size 1 1)
					(thickness 0.15)
				)
			)
		)
		(property "License" "Apache-2.0"
			(at 0 0 180)
			(unlocked yes)
			(layer "F.Fab")
			(hide yes)
			(effects
				(font
					(size 1 1)
					(thickness 0.15)
				)
			)
		)
		(sheetname "/Power/")
		(sheetfile "power.kicad_sch")
		(attr smd)
		(fp_line
			(start 1.648 -1.651)
			(end 1.648 -1.317)
			(stroke
				(width 0.15)
				(type solid)
			)
			(layer "F.SilkS")
		)
		(fp_line
			(start 1.634 1.3)
			(end 1.634 1.634)
			(stroke
				(width 0.15)
				(type solid)
			)
			(layer "F.SilkS")
		)
		(fp_line
			(start -1.635 1.634)
			(end 1.634 1.634)
			(stroke
				(width 0.15)
				(type solid)
			)
			(layer "F.SilkS")
		)
		(fp_line
			(start -1.635 1.3)
			(end -1.635 1.634)
			(stroke
				(width 0.15)
				(type solid)
			)
			(layer "F.SilkS")
		)
		(fp_line
			(start -1.651 -1.651)
			(end 1.648 -1.651)
			(stroke
				(width 0.15)
				(type solid)
			)
			(layer "F.SilkS")
		)
		(fp_line
			(start -1.651 -1.651)
			(end -1.651 -1.317)
			(stroke
				(width 0.15)
				(type solid)
			)
			(layer "F.SilkS")
		)
		(fp_circle
			(center -1.9 -1.4)
			(end -1.85 -1.4)
			(stroke
				(width 0.15)
				(type solid)
			)
			(fill yes)
			(layer "F.SilkS")
		)
		(fp_rect
			(start -2 -1.8)
			(end 2 1.798)
			(stroke
				(width 0.05)
				(type solid)
			)
			(fill no)
			(layer "F.CrtYd")
		)
		(fp_line
			(start -1.6425 -1.4175)
			(end -1.4175 -1.6425)
			(stroke
				(width 0.15)
				(type solid)
			)
			(layer "F.Fab")
		)
		(fp_rect
			(start -1.651 -1.651)
			(end 1.648 1.648)
			(stroke
				(width 0.15)
				(type solid)
			)
			(fill no)
			(layer "F.Fab")
		)
		(fp_text user "Author: Antmicro"
			(at -8 5.9 0)
			(layer "F.Fab")
			(effects
				(font
					(size 0.7 0.7)
					(thickness 0.15)
				)
				(justify right top)
			)
		)
		(fp_text user "License: Apache-2.0"
			(at -8 7.1 0)
			(layer "F.Fab")
			(effects
				(font
					(size 0.7 0.7)
					(thickness 0.15)
				)
				(justify right top)
			)
		)
		(fp_text user "${REFERENCE}"
			(at -8 4.7 0)
			(layer "F.Fab")
			(effects
				(font
					(size 0.7 0.7)
					(thickness 0.15)
				)
				(justify right top)
			)
		)
		(pad "1" smd rect
			(at -1.436 -0.99 180)
			(size 0.99 0.405)
			(layers "F.Cu" "F.Mask" "F.Paste")
			(net 1383 "VCC_NO_OVP")
			(pinfunction "S")
			(pintype "passive")
		)
		(pad "2" smd rect
			(at -1.436 -0.332 180)
			(size 0.99 0.405)
			(layers "F.Cu" "F.Mask" "F.Paste")
			(net 1383 "VCC_NO_OVP")
			(pinfunction "S")
			(pintype "passive")
		)
		(pad "3" smd rect
			(at -1.436 0.33 180)
			(size 0.99 0.405)
			(layers "F.Cu" "F.Mask" "F.Paste")
			(net 1383 "VCC_NO_OVP")
			(pinfunction "S")
			(pintype "passive")
		)
		(pad "4" smd rect
			(at -1.436 0.988 180)
			(size 0.99 0.405)
			(layers "F.Cu" "F.Mask" "F.Paste")
			(net 1385 "Net-(Q41-G)")
			(pinfunction "G")
			(pintype "input")
		)
		(pad "5" smd custom
			(at 0.557 0 180)
			(size 1.725 2.235)
			(layers "F.Cu" "F.Mask" "F.Paste")
			(net 13 "VCC")
			(pinfunction "D")
			(pintype "passive")
			(zone_connect 2)
			(options
				(clearance outline)
				(anchor rect)
			)
			(primitives
				(gr_poly
					(pts
						(xy 0.8625 0.1275) (xy 0.8625 -0.1275) (xy 1.3725 -0.1275) (xy 1.3725 -0.5325) (xy 0.8625 -0.5325)
						(xy 0.8625 -0.7875) (xy 1.3725 -0.7875) (xy 1.3725 -1.195) (xy 0.6125 -1.195) (xy 0.6125 1.195)
						(xy 1.3725 1.195) (xy 1.3725 0.7875) (xy 0.8625 0.7875) (xy 0.8625 0.5325) (xy 1.3725 0.5325)
						(xy 1.3725 0.1275)
					)
					(width 0)
					(fill yes)
				)
			)
		)
	)
)
